(kicad_pcb
	(version 20260206)
	(generator "pcbnew")
	(generator_version "10.0")
	(general
		(thickness 1.6)
		(legacy_teardrops no)
	)
	(paper "A4")
	(title_block
		(title "timecard-production-celestica-r4006 — R4006-B0001-02_R01.brd")
		(comment 1 "Time Appliance Project (Time Card) / footprints 131-134 of 1113")
	)
	(layers
		(0 "F.Cu" signal "TOP")
		(4 "In1.Cu" signal "L02_GND1")
		(6 "In2.Cu" signal "L03_SIG1")
		(8 "In3.Cu" signal "L04_GND2")
		(10 "In4.Cu" signal "L05_VCC1")
		(12 "In5.Cu" signal "L06_VCC2")
		(14 "In6.Cu" signal "L07_GND3")
		(16 "In7.Cu" signal "L08_SIG2")
		(18 "In8.Cu" signal "L09_GND4")
		(2 "B.Cu" signal "BOTTOM")
		(9 "F.Adhes" user "F.Adhesive")
		(11 "B.Adhes" user "B.Adhesive")
		(13 "F.Paste" user "Package Geometry/Pastemask Top")
		(15 "B.Paste" user "Package Geometry/Pastemask Bottom")
		(5 "F.SilkS" user "Ref Des/Silkscreen Top")
		(7 "B.SilkS" user "Ref Des/Silkscreen Bottom")
		(1 "F.Mask" user "Board Geometry/Soldermask Top")
		(3 "B.Mask" user "Board Geometry/Soldermask Bottom")
		(17 "Dwgs.User" user "User.Drawings")
		(19 "Cmts.User" user "User.Comments")
		(21 "Eco1.User" user "User.Eco1")
		(23 "Eco2.User" user "User.Eco2")
		(25 "Edge.Cuts" user "Board Geometry/Outline")
		(27 "Margin" user)
		(31 "F.CrtYd" user "Package Geometry/Place Bound Top")
		(29 "B.CrtYd" user "Package Geometry/Place Bound Bottom")
		(35 "F.Fab" user "Ref Des/Assembly Top")
		(33 "B.Fab" user "Ref Des/Assembly Bottom")
	)
	(footprint ""
		(layer "F.Cu")
		(at 162.569906 -16.599916)
		(property "Reference" "ME12"
			(at 0.371094 -4.188714 0)
			(unlocked yes)
			(layer "F.SilkS")
			(effects
				(font
					(size 0.7874 0.5842)
					(thickness 0.1524)
				)
			)
		)
		(property "Value" ""
			(at 0 0 0)
			(layer "F.Fab")
			(effects
				(font
					(size 1.27 1.27)
				)
			)
		)
		(property "Device Type" "MEC_MTH8-MTH125C236N_V8-MTH125A"
			(at 0 5.08127 0)
			(unlocked yes)
			(layer "F.Fab")
			(hide yes)
			(effects
				(font
					(size 0.7874 0.5842)
					(thickness 0.1524)
				)
			)
		)
		(duplicate_pad_numbers_are_jumpers no)
		(fp_poly
			(pts
				(arc
					(start 3.5052 0)
					(mid -3.5052 0)
					(end 3.5052 0)
				)
			)
			(stroke
				(width 0)
				(type default)
			)
			(fill no)
			(layer "B.CrtYd")
		)
		(fp_poly
			(pts
				(arc
					(start 3.5052 0)
					(mid -3.5052 0)
					(end 3.5052 0)
				)
			)
			(stroke
				(width 0)
				(type default)
			)
			(fill no)
			(layer "F.CrtYd")
		)
		(fp_circle
			(center 0 0)
			(end 2.9972 0)
			(stroke
				(width 0.1)
				(type default)
			)
			(fill no)
			(layer "B.Fab")
		)
		(fp_circle
			(center 0 0)
			(end 2.9972 0)
			(stroke
				(width 0.1)
				(type default)
			)
			(fill no)
			(layer "F.Fab")
		)
		(pad "" np_thru_hole circle
			(at 0 0)
			(size 2.921 2.921)
			(drill 3.175)
			(layers "*.Cu" "*.Mask")
			(padstack
				(mode front_inner_back)
				(layer "Inner"
					(shape circle)
					(size 2.921 2.921)
					(clearance 0.4445)
				)
				(layer "B.Cu"
					(shape circle)
					(size 2.921 2.921)
				)
			)
		)
		(pad "1" thru_hole circle
			(at 0 -2.4511)
			(size 0.6096 0.6096)
			(drill 0.3048)
			(layers "*.Cu" "*.Mask")
			(remove_unused_layers no)
			(net "SG")
			(padstack
				(mode front_inner_back)
				(layer "Inner"
					(shape circle)
					(size 0.6096 0.6096)
					(clearance 0.1143)
				)
				(layer "B.Cu"
					(shape circle)
					(size 0.6096 0.6096)
				)
			)
		)
		(pad "2" thru_hole circle
			(at 1.733296 -1.733296)
			(size 0.6096 0.6096)
			(drill 0.3048)
			(layers "*.Cu" "*.Mask")
			(remove_unused_layers no)
			(net "SG")
			(padstack
				(mode front_inner_back)
				(layer "Inner"
					(shape circle)
					(size 0.6096 0.6096)
					(clearance 0.1143)
				)
				(layer "B.Cu"
					(shape circle)
					(size 0.6096 0.6096)
				)
			)
		)
		(pad "3" thru_hole circle
			(at 2.4511 0)
			(size 0.6096 0.6096)
			(drill 0.3048)
			(layers "*.Cu" "*.Mask")
			(remove_unused_layers no)
			(net "SG")
			(padstack
				(mode front_inner_back)
				(layer "Inner"
					(shape circle)
					(size 0.6096 0.6096)
					(clearance 0.1143)
				)
				(layer "B.Cu"
					(shape circle)
					(size 0.6096 0.6096)
				)
			)
		)
		(pad "4" thru_hole circle
			(at 1.733296 1.733296)
			(size 0.6096 0.6096)
			(drill 0.3048)
			(layers "*.Cu" "*.Mask")
			(remove_unused_layers no)
			(net "SG")
			(padstack
				(mode front_inner_back)
				(layer "Inner"
					(shape circle)
					(size 0.6096 0.6096)
					(clearance 0.1143)
				)
				(layer "B.Cu"
					(shape circle)
					(size 0.6096 0.6096)
				)
			)
		)
		(pad "5" thru_hole circle
			(at 0 2.4511)
			(size 0.6096 0.6096)
			(drill 0.3048)
			(layers "*.Cu" "*.Mask")
			(remove_unused_layers no)
			(net "SG")
			(padstack
				(mode front_inner_back)
				(layer "Inner"
					(shape circle)
					(size 0.6096 0.6096)
					(clearance 0.1143)
				)
				(layer "B.Cu"
					(shape circle)
					(size 0.6096 0.6096)
				)
			)
		)
		(pad "6" thru_hole circle
			(at -1.733296 1.733296)
			(size 0.6096 0.6096)
			(drill 0.3048)
			(layers "*.Cu" "*.Mask")
			(remove_unused_layers no)
			(net "SG")
			(padstack
				(mode front_inner_back)
				(layer "Inner"
					(shape circle)
					(size 0.6096 0.6096)
					(clearance 0.1143)
				)
				(layer "B.Cu"
					(shape circle)
					(size 0.6096 0.6096)
				)
			)
		)
		(pad "7" thru_hole circle
			(at -2.4511 0)
			(size 0.6096 0.6096)
			(drill 0.3048)
			(layers "*.Cu" "*.Mask")
			(remove_unused_layers no)
			(net "SG")
			(padstack
				(mode front_inner_back)
				(layer "Inner"
					(shape circle)
					(size 0.6096 0.6096)
					(clearance 0.1143)
				)
				(layer "B.Cu"
					(shape circle)
					(size 0.6096 0.6096)
				)
			)
		)
		(pad "8" thru_hole circle
			(at -1.733296 -1.733296)
			(size 0.6096 0.6096)
			(drill 0.3048)
			(layers "*.Cu" "*.Mask")
			(remove_unused_layers no)
			(net "SG")
			(padstack
				(mode front_inner_back)
				(layer "Inner"
					(shape circle)
					(size 0.6096 0.6096)
					(clearance 0.1143)
				)
				(layer "B.Cu"
					(shape circle)
					(size 0.6096 0.6096)
				)
			)
		)
		(zone
			(layers "F.Cu" "B.Cu" "In1.Cu" "In2.Cu" "In3.Cu" "In4.Cu" "In5.Cu" "In6.Cu"
				"In7.Cu" "In8.Cu"
			)
			(hatch none 0.5)
			(connect_pads
				(clearance 0)
			)
			(min_thickness 0.25)
			(keepout
				(tracks not_allowed)
				(vias allowed)
				(pads allowed)
				(copperpour not_allowed)
				(footprints allowed)
			)
			(placement
				(enabled no)
				(sheetname "")
			)
			(fill
				(thermal_gap 0.5)
				(thermal_bridge_width 0.5)
				(island_removal_mode 0)
			)
			(polygon
				(pts
					(arc
						(start 164.462206 -16.599916)
						(mid 160.677606 -16.599916)
						(end 164.462206 -16.599916)
					)
				)
			)
		)
	)
	(footprint ""
		(layer "F.Cu")
		(at 8.382 -81.534 90)
		(property "Reference" "R399"
			(at -2.667 -0.59563 90)
			(unlocked yes)
			(layer "F.SilkS")
			(effects
				(font
					(size 0.7874 0.5842)
					(thickness 0.1524)
				)
			)
		)
		(property "Value" "VAL*"
			(at 0.02032 2.13233 90)
			(unlocked yes)
			(layer "F.Fab")
			(hide yes)
			(effects
				(font
					(size 0.7874 0.5842)
					(thickness 0.1524)
				)
			)
		)
		(property "Tolerance" "TOL*"
			(at 0.044704 3.05435 90)
			(unlocked yes)
			(layer "Cmts.User")
			(hide yes)
			(effects
				(font
					(size 0.7874 0.5842)
					(thickness 0.1524)
				)
			)
		)
		(property "User Part Number" "PARTNUM*"
			(at 0.02032 4.024884 90)
			(unlocked yes)
			(layer "Cmts.User")
			(hide yes)
			(effects
				(font
					(size 0.7874 0.5842)
					(thickness 0.1524)
				)
			)
		)
		(property "Device Type" "RESISTOR-G155-133R0-01,33OHM,1%"
			(at 0.008382 1.210564 90)
			(unlocked yes)
			(layer "F.Fab")
			(hide yes)
			(effects
				(font
					(size 0.7874 0.5842)
					(thickness 0.1524)
				)
			)
		)
		(duplicate_pad_numbers_are_jumpers no)
		(fp_line
			(start 1.143 -0.5588)
			(end -1.143 -0.5588)
			(stroke
				(width 0.1)
				(type default)
			)
			(layer "F.SilkS")
		)
		(fp_line
			(start -1.143 -0.5588)
			(end -1.143 0.5588)
			(stroke
				(width 0.1)
				(type default)
			)
			(layer "F.SilkS")
		)
		(fp_line
			(start 1.143 0.5588)
			(end 1.143 -0.5588)
			(stroke
				(width 0.1)
				(type default)
			)
			(layer "F.SilkS")
		)
		(fp_line
			(start -1.143 0.5588)
			(end 1.143 0.5588)
			(stroke
				(width 0.1)
				(type default)
			)
			(layer "F.SilkS")
		)
		(fp_rect
			(start -1.143 -0.5588)
			(end 1.143 0.5588)
			(stroke
				(width 0)
				(type default)
			)
			(fill no)
			(layer "F.CrtYd")
		)
		(fp_line
			(start 0.508 -0.3048)
			(end -0.508 -0.3048)
			(stroke
				(width 0.1)
				(type default)
			)
			(layer "F.Fab")
		)
		(fp_line
			(start -0.508 -0.3048)
			(end -0.508 0.3048)
			(stroke
				(width 0.1)
				(type default)
			)
			(layer "F.Fab")
		)
		(fp_line
			(start 0.508 0.3048)
			(end 0.508 -0.3048)
			(stroke
				(width 0.1)
				(type default)
			)
			(layer "F.Fab")
		)
		(fp_line
			(start -0.508 0.3048)
			(end 0.508 0.3048)
			(stroke
				(width 0.1)
				(type default)
			)
			(layer "F.Fab")
		)
		(pad "1" smd rect
			(at -0.5334 0 90)
			(size 0.7112 0.6096)
			(layers "F.Cu" "F.Mask" "F.Paste")
			(net "GPS_SMA_LED_RED_N")
		)
		(pad "2" smd rect
			(at 0.5334 0 90)
			(size 0.7112 0.6096)
			(layers "F.Cu" "F.Mask" "F.Paste")
			(net "UNNAMED_14_LED4PV14_I269_3")
		)
		(zone
			(layer "F.Cu")
			(hatch none 0.5)
			(connect_pads
				(clearance 0)
			)
			(min_thickness 0.25)
			(keepout
				(tracks not_allowed)
				(vias allowed)
				(pads allowed)
				(copperpour not_allowed)
				(footprints allowed)
			)
			(placement
				(enabled no)
				(sheetname "")
			)
			(fill
				(thermal_gap 0.5)
				(thermal_bridge_width 0.5)
				(island_removal_mode 0)
			)
			(polygon
				(pts
					(xy 8.0772 -81.4578) (xy 8.6868 -81.4578) (xy 8.6868 -81.6102) (xy 8.0772 -81.6102)
				)
			)
		)
		(zone
			(layer "F.Cu")
			(hatch none 0.5)
			(connect_pads
				(clearance 0)
			)
			(min_thickness 0.25)
			(keepout
				(tracks allowed)
				(vias not_allowed)
				(pads allowed)
				(copperpour not_allowed)
				(footprints allowed)
			)
			(placement
				(enabled no)
				(sheetname "")
			)
			(fill
				(thermal_gap 0.5)
				(thermal_bridge_width 0.5)
				(island_removal_mode 0)
			)
			(polygon
				(pts
					(xy 8.0772 -81.4578) (xy 8.6868 -81.4578) (xy 8.6868 -81.6102) (xy 8.0772 -81.6102)
				)
			)
		)
	)
	(footprint ""
		(layer "F.Cu")
		(at 20.052792 -67.5894 180)
		(property "Reference" "U28"
			(at 0.494792 2.09423 0)
			(unlocked yes)
			(layer "F.SilkS")
			(effects
				(font
					(size 0.7874 0.5842)
					(thickness 0.1524)
				)
			)
		)
		(property "Value" ""
			(at 0 0 180)
			(layer "F.Fab")
			(effects
				(font
					(size 1.27 1.27)
				)
			)
		)
		(property "Device Type" "ICP_10100_LGA10-A222-00002-FB,A"
			(at 0.0635 3.182112 180)
			(unlocked yes)
			(layer "F.Fab")
			(hide yes)
			(effects
				(font
					(size 0.7874 0.5842)
					(thickness 0.1524)
				)
			)
		)
		(property "User Part Number" "PARTNUM*"
			(at 0.0635 4.375912 180)
			(unlocked yes)
			(layer "Cmts.User")
			(hide yes)
			(effects
				(font
					(size 0.7874 0.5842)
					(thickness 0.1524)
				)
			)
		)
		(duplicate_pad_numbers_are_jumpers no)
		(fp_line
			(start 1.304036 1.304036)
			(end -1.304036 1.304036)
			(stroke
				(width 0.1)
				(type default)
			)
			(layer "F.SilkS")
		)
		(fp_line
			(start 1.304036 -1.304036)
			(end 1.304036 1.304036)
			(stroke
				(width 0.1)
				(type default)
			)
			(layer "F.SilkS")
		)
		(fp_line
			(start -1.304036 1.304036)
			(end -1.304036 -1.304036)
			(stroke
				(width 0.1)
				(type default)
			)
			(layer "F.SilkS")
		)
		(fp_line
			(start -1.304036 -1.304036)
			(end 1.304036 -1.304036)
			(stroke
				(width 0.1)
				(type default)
			)
			(layer "F.SilkS")
		)
		(fp_poly
			(pts
				(arc
					(start -2.172208 2.2606)
					(mid -1.156716 2.2606)
					(end -2.172208 2.2606)
				)
			)
			(stroke
				(width 0)
				(type default)
			)
			(fill yes)
			(layer "F.SilkS")
		)
		(fp_rect
			(start 1.558036 1.558036)
			(end -1.558036 -1.558036)
			(stroke
				(width 0)
				(type default)
			)
			(fill no)
			(layer "F.CrtYd")
		)
		(fp_line
			(start 1.050036 1.050036)
			(end -1.050036 1.050036)
			(stroke
				(width 0.1)
				(type default)
			)
			(layer "F.Fab")
		)
		(fp_line
			(start 1.050036 -1.050036)
			(end 1.050036 1.050036)
			(stroke
				(width 0.1)
				(type default)
			)
			(layer "F.Fab")
		)
		(fp_line
			(start -1.050036 1.050036)
			(end -1.050036 -1.050036)
			(stroke
				(width 0.1)
				(type default)
			)
			(layer "F.Fab")
		)
		(fp_line
			(start -1.050036 -1.050036)
			(end 1.050036 -1.050036)
			(stroke
				(width 0.1)
				(type default)
			)
			(layer "F.Fab")
		)
		(fp_poly
			(pts
				(arc
					(start -1.200658 2.133854)
					(mid -0.185166 2.133854)
					(end -1.200658 2.133854)
				)
			)
			(stroke
				(width 0)
				(type default)
			)
			(fill yes)
			(layer "F.Fab")
		)
		(fp_text user "2"
			(at 1.891792 2.10185 0)
			(unlocked yes)
			(layer "F.SilkS")
			(effects
				(font
					(size 0.635 0.4064)
					(thickness 0.1524)
				)
			)
		)
		(fp_text user "5"
			(at 1.759458 -0.96139 0)
			(unlocked yes)
			(layer "F.SilkS")
			(effects
				(font
					(size 0.635 0.4064)
					(thickness 0.1524)
				)
			)
		)
		(fp_text user "3"
			(at 1.693418 0.212598 0)
			(unlocked yes)
			(layer "F.SilkS")
			(effects
				(font
					(size 0.635 0.4064)
					(thickness 0.1524)
				)
			)
		)
		(fp_text user "6"
			(at 1.510792 -1.83515 0)
			(unlocked yes)
			(layer "F.SilkS")
			(effects
				(font
					(size 0.635 0.4064)
					(thickness 0.1524)
				)
			)
		)
		(fp_text user "8"
			(at -1.918208 -1.45415 0)
			(unlocked yes)
			(layer "F.SilkS")
			(effects
				(font
					(size 0.635 0.4064)
					(thickness 0.1524)
				)
			)
		)
		(fp_text user "3"
			(at 1.637792 1.09093 0)
			(unlocked yes)
			(layer "F.Fab")
			(effects
				(font
					(size 0.7874 0.5842)
					(thickness 0.1524)
				)
			)
		)
		(fp_text user "5"
			(at 1.383792 -0.56007 0)
			(unlocked yes)
			(layer "F.Fab")
			(effects
				(font
					(size 0.7874 0.5842)
					(thickness 0.1524)
				)
			)
		)
		(fp_text user "6"
			(at 1.383792 -1.70307 0)
			(unlocked yes)
			(layer "F.Fab")
			(effects
				(font
					(size 0.7874 0.5842)
					(thickness 0.1524)
				)
			)
		)
		(fp_text user "2"
			(at 0.621792 1.72593 0)
			(unlocked yes)
			(layer "F.Fab")
			(effects
				(font
					(size 0.7874 0.5842)
					(thickness 0.1524)
				)
			)
		)
		(fp_text user "7"
			(at -0.521208 -1.70307 0)
			(unlocked yes)
			(layer "F.Fab")
			(effects
				(font
					(size 0.7874 0.5842)
					(thickness 0.1524)
				)
			)
		)
		(fp_text user "8"
			(at -1.664208 -0.68707 0)
			(unlocked yes)
			(layer "F.Fab")
			(effects
				(font
					(size 0.7874 0.5842)
					(thickness 0.1524)
				)
			)
		)
		(fp_text user "10"
			(at -1.791208 1.47193 0)
			(unlocked yes)
			(layer "F.Fab")
			(effects
				(font
					(size 0.7874 0.5842)
					(thickness 0.1524)
				)
			)
		)
		(pad "1" smd rect
			(at -0.249936 0.774954 180)
			(size 0.2794 0.3556)
			(layers "F.Cu" "F.Mask" "F.Paste")
			(net "UNNAMED_8_ICP10100LGA10_I24_RES")
		)
		(pad "2" smd rect
			(at 0.249936 0.774954 180)
			(size 0.2794 0.3556)
			(layers "F.Cu" "F.Mask" "F.Paste")
			(net "R_ICP10100_I2C_SCL")
		)
		(pad "3" smd rect
			(at 0.774954 0.500126 180)
			(size 0.3556 0.2794)
			(layers "F.Cu" "F.Mask" "F.Paste")
			(net "UNNAMED_8_ICP10100LGA10_I24_R_1")
		)
		(pad "4" smd rect
			(at 0.774954 0 180)
			(size 0.3556 0.2794)
			(layers "F.Cu" "F.Mask" "F.Paste")
			(net "R_ICP10100_I2C_SDA")
		)
		(pad "5" smd rect
			(at 0.774954 -0.500126 180)
			(size 0.3556 0.2794)
			(layers "F.Cu" "F.Mask" "F.Paste")
			(net "UNNAMED_8_ICP10100LGA10_I24_R_2")
		)
		(pad "6" smd rect
			(at 0.249936 -0.774954 180)
			(size 0.2794 0.3556)
			(layers "F.Cu" "F.Mask" "F.Paste")
			(net "UNNAMED_8_ICP10100LGA10_I24_R_3")
		)
		(pad "7" smd rect
			(at -0.249936 -0.774954 180)
			(size 0.2794 0.3556)
			(layers "F.Cu" "F.Mask" "F.Paste")
			(net "UNNAMED_8_ICP10100LGA10_I24_R_4")
		)
		(pad "8" smd rect
			(at -0.774954 -0.500126 180)
			(size 0.3556 0.2794)
			(layers "F.Cu" "F.Mask" "F.Paste")
			(net "SG")
		)
		(pad "9" smd rect
			(at -0.774954 0 180)
			(size 0.3556 0.2794)
			(layers "F.Cu" "F.Mask" "F.Paste")
			(net "SG")
		)
		(pad "10" smd rect
			(at -0.774954 0.500126 180)
			(size 0.3556 0.2794)
			(layers "F.Cu" "F.Mask" "F.Paste")
			(net "XP1R8V_ICP10100")
		)
	)
	(footprint ""
		(layer "F.Cu")
		(at 126.492 -36.322)
		(property "Reference" "R222"
			(at 2.921 1.56337 0)
			(unlocked yes)
			(layer "F.SilkS")
			(effects
				(font
					(size 0.7874 0.5842)
					(thickness 0.1524)
				)
			)
		)
		(property "Value" "VAL*"
			(at 0.02032 2.13233 0)
			(unlocked yes)
			(layer "F.Fab")
			(hide yes)
			(effects
				(font
					(size 0.7874 0.5842)
					(thickness 0.1524)
				)
			)
		)
		(property "Device Type" "RESISTOR-G155-11000-01,100OHM,A"
			(at 0.008382 1.210564 0)
			(unlocked yes)
			(layer "F.Fab")
			(hide yes)
			(effects
				(font
					(size 0.7874 0.5842)
					(thickness 0.1524)
				)
			)
		)
		(property "User Part Number" "PARTNUM*"
			(at 0.02032 4.024884 0)
			(unlocked yes)
			(layer "Cmts.User")
			(hide yes)
			(effects
				(font
					(size 0.7874 0.5842)
					(thickness 0.1524)
				)
			)
		)
		(property "Tolerance" "TOL*"
			(at 0.044704 3.05435 0)
			(unlocked yes)
			(layer "Cmts.User")
			(hide yes)
			(effects
				(font
					(size 0.7874 0.5842)
					(thickness 0.1524)
				)
			)
		)
		(duplicate_pad_numbers_are_jumpers no)
		(fp_line
			(start -1.143 -0.5588)
			(end -1.143 0.5588)
			(stroke
				(width 0.1)
				(type default)
			)
			(layer "F.SilkS")
		)
		(fp_line
			(start -1.143 0.5588)
			(end 1.143 0.5588)
			(stroke
				(width 0.1)
				(type default)
			)
			(layer "F.SilkS")
		)
		(fp_line
			(start 1.143 -0.5588)
			(end -1.143 -0.5588)
			(stroke
				(width 0.1)
				(type default)
			)
			(layer "F.SilkS")
		)
		(fp_line
			(start 1.143 0.5588)
			(end 1.143 -0.5588)
			(stroke
				(width 0.1)
				(type default)
			)
			(layer "F.SilkS")
		)
		(fp_rect
			(start -1.143 0.5588)
			(end 1.143 -0.5588)
			(stroke
				(width 0)
				(type default)
			)
			(fill no)
			(layer "F.CrtYd")
		)
		(fp_line
			(start -0.508 -0.3048)
			(end -0.508 0.3048)
			(stroke
				(width 0.1)
				(type default)
			)
			(layer "F.Fab")
		)
		(fp_line
			(start -0.508 0.3048)
			(end 0.508 0.3048)
			(stroke
				(width 0.1)
				(type default)
			)
			(layer "F.Fab")
		)
		(fp_line
			(start 0.508 -0.3048)
			(end -0.508 -0.3048)
			(stroke
				(width 0.1)
				(type default)
			)
			(layer "F.Fab")
		)
		(fp_line
			(start 0.508 0.3048)
			(end 0.508 -0.3048)
			(stroke
				(width 0.1)
				(type default)
			)
			(layer "F.Fab")
		)
		(pad "1" smd rect
			(at -0.5334 0)
			(size 0.7112 0.6096)
			(layers "F.Cu" "F.Mask" "F.Paste")
			(net "FPGA_M2")
		)
		(pad "2" smd rect
			(at 0.5334 0)
			(size 0.7112 0.6096)
			(layers "F.Cu" "F.Mask" "F.Paste")
			(net "SG")
		)
		(zone
			(layer "F.Cu")
			(hatch none 0.5)
			(connect_pads
				(clearance 0)
			)
			(min_thickness 0.25)
			(keepout
				(tracks allowed)
				(vias not_allowed)
				(pads allowed)
				(copperpour not_allowed)
				(footprints allowed)
			)
			(placement
				(enabled no)
				(sheetname "")
			)
			(fill
				(thermal_gap 0.5)
				(thermal_bridge_width 0.5)
				(island_removal_mode 0)
			)
			(polygon
				(pts
					(xy 126.4158 -36.0172) (xy 126.5682 -36.0172) (xy 126.5682 -36.6268) (xy 126.4158 -36.6268)
				)
			)
		)
	)
)
